# S9S_MB_2U (Grand Teton) — schematic netlist excerpt (pin names and nets, part order shuffled) for the footprints in the layout excerpt that follows; sources: Cadence DE-HDL packaged netlist, KiCad conversion of 03242023_DA0F0TMBIJ0_F0T_Motherboard_J_brd_V01_OCP.brd

PC1212_P0_2  Q_CAP  2.2UF 10V 10% X6S  pkg C0402  page 271 : A = PVCCFA_EHV_FIVRA_CPU0_PVCC2 ; B = GND
R4779  Q_RES  1M 1% CHIP  pkg 0402LF  page 307 : A = P12V_AUX_UV_TRIGGER ; B = IRQ_UV_DETECT_R2_N

(kicad_pcb
	(version 20260206)
	(generator "pcbnew")
	(generator_version "10.0")
	(general
		(thickness 1.6)
		(legacy_teardrops no)
	)
	(paper "A4")
	(title_block
		(title "03242023_DA0F0TMBIJ0_F0T_Motherboard_J_brd_V01_OCP.brd")
		(comment 1 "Grand Teton / footprints 773-774 of 6105")
	)
	(layers
		(0 "F.Cu" signal "TOP")
		(4 "In1.Cu" signal "GND")
		(6 "In2.Cu" signal "IN1")
		(8 "In3.Cu" signal "GND1")
		(10 "In4.Cu" signal "IN2")
		(12 "In5.Cu" signal "GND2")
		(14 "In6.Cu" signal "IN3")
		(16 "In7.Cu" signal "GND3")
		(18 "In8.Cu" signal "VCC")
		(20 "In9.Cu" signal "VCC1")
		(22 "In10.Cu" signal "GND4")
		(24 "In11.Cu" signal "IN4")
		(26 "In12.Cu" signal "GND5")
		(28 "In13.Cu" signal "IN5")
		(30 "In14.Cu" signal "GND6")
		(32 "In15.Cu" signal "IN6")
		(34 "In16.Cu" signal "GND7")
		(2 "B.Cu" signal "BOTTOM")
		(9 "F.Adhes" user "F.Adhesive")
		(11 "B.Adhes" user "B.Adhesive")
		(13 "F.Paste" user "Package Geometry/Pastemask Top")
		(15 "B.Paste" user "Package Geometry/Pastemask Bottom")
		(5 "F.SilkS" user "Ref Des/Silkscreen Top")
		(7 "B.SilkS" user "Ref Des/Silkscreen Bottom")
		(1 "F.Mask" user "Board Geometry/Soldermask Top")
		(3 "B.Mask" user "Board Geometry/Soldermask Bottom")
		(17 "Dwgs.User" user "User.Drawings")
		(19 "Cmts.User" user "User.Comments")
		(21 "Eco1.User" user "User.Eco1")
		(23 "Eco2.User" user "User.Eco2")
		(25 "Edge.Cuts" user "Board Geometry/Outline")
		(27 "Margin" user)
		(31 "F.CrtYd" user "Package Geometry/Place Bound Top")
		(29 "B.CrtYd" user "Package Geometry/Place Bound Bottom")
		(35 "F.Fab" user "Ref Des/Assembly Top")
		(33 "B.Fab" user "Ref Des/Assembly Bottom")
	)
	(footprint ""
		(layer "F.Cu")
		(at 215.646 -111.6838 90)
		(property "Reference" "R4779"
			(at 0 0 90)
			(layer "F.SilkS")
			(hide yes)
			(effects
				(font
					(size 1.27 1.27)
				)
			)
		)
		(property "Value" ""
			(at 0 0 90)
			(layer "F.Fab")
			(effects
				(font
					(size 1.27 1.27)
				)
			)
		)
		(duplicate_pad_numbers_are_jumpers no)
		(fp_line
			(start 0.7874 -0.4064)
			(end 0.7874 0.4064)
			(stroke
				(width 0.1524)
				(type default)
			)
			(layer "F.SilkS")
		)
		(fp_line
			(start -0.7874 -0.4064)
			(end 0.7874 -0.4064)
			(stroke
				(width 0.1524)
				(type default)
			)
			(layer "F.SilkS")
		)
		(fp_line
			(start 0.7874 0.4064)
			(end -0.7874 0.4064)
			(stroke
				(width 0.1524)
				(type default)
			)
			(layer "F.SilkS")
		)
		(fp_line
			(start -0.7874 0.4064)
			(end -0.7874 -0.4064)
			(stroke
				(width 0.1524)
				(type default)
			)
			(layer "F.SilkS")
		)
		(fp_line
			(start -0.12065 -0.305054)
			(end -0.12065 -0.2794)
			(stroke
				(width 0.1)
				(type default)
			)
			(layer "F.Fab")
		)
		(fp_line
			(start -0.67945 -0.305054)
			(end -0.12065 -0.305054)
			(stroke
				(width 0.1)
				(type default)
			)
			(layer "F.Fab")
		)
		(fp_line
			(start 0.67945 -0.3048)
			(end 0.67945 0.3048)
			(stroke
				(width 0.1)
				(type default)
			)
			(layer "F.Fab")
		)
		(fp_line
			(start 0.12065 -0.3048)
			(end 0.67945 -0.3048)
			(stroke
				(width 0.1)
				(type default)
			)
			(layer "F.Fab")
		)
		(fp_line
			(start 0.12065 -0.2794)
			(end 0.12065 -0.3048)
			(stroke
				(width 0.1)
				(type default)
			)
			(layer "F.Fab")
		)
		(fp_line
			(start -0.12065 -0.2794)
			(end 0.12065 -0.2794)
			(stroke
				(width 0.1)
				(type default)
			)
			(layer "F.Fab")
		)
		(fp_line
			(start 0.120396 0.2794)
			(end -0.12065 0.2794)
			(stroke
				(width 0.1)
				(type default)
			)
			(layer "F.Fab")
		)
		(fp_line
			(start -0.12065 0.2794)
			(end -0.12065 0.3048)
			(stroke
				(width 0.1)
				(type default)
			)
			(layer "F.Fab")
		)
		(fp_line
			(start 0.67945 0.3048)
			(end 0.120396 0.3048)
			(stroke
				(width 0.1)
				(type default)
			)
			(layer "F.Fab")
		)
		(fp_line
			(start 0.120396 0.3048)
			(end 0.120396 0.2794)
			(stroke
				(width 0.1)
				(type default)
			)
			(layer "F.Fab")
		)
		(fp_line
			(start -0.12065 0.3048)
			(end -0.67945 0.3048)
			(stroke
				(width 0.1)
				(type default)
			)
			(layer "F.Fab")
		)
		(fp_line
			(start -0.67945 0.3048)
			(end -0.67945 -0.305054)
			(stroke
				(width 0.1)
				(type default)
			)
			(layer "F.Fab")
		)
		(pad "1" smd circle
			(at -0.40005 0 90)
			(size 0 0)
			(layers "F.Cu" "F.Mask" "F.Paste")
			(net "P12V_AUX_UV_TRIGGER")
		)
		(pad "2" smd circle
			(at 0.40005 0 90)
			(size 0 0)
			(layers "F.Cu" "F.Mask" "F.Paste")
			(net "IRQ_UV_DETECT_R2_N")
		)
	)
	(footprint ""
		(layer "F.Cu")
		(at 294.899588 -362.584746 -90)
		(property "Reference" "PC1212_P0_2"
			(at 0 0 270)
			(layer "F.SilkS")
			(hide yes)
			(effects
				(font
					(size 1.27 1.27)
				)
			)
		)
		(property "Value" ""
			(at 0 0 270)
			(layer "F.Fab")
			(effects
				(font
					(size 1.27 1.27)
				)
			)
		)
		(duplicate_pad_numbers_are_jumpers no)
		(fp_line
			(start -0.7874 0.4064)
			(end -0.7874 -0.4064)
			(stroke
				(width 0.1524)
				(type default)
			)
			(layer "F.SilkS")
		)
		(fp_line
			(start 0.7874 0.4064)
			(end -0.7874 0.4064)
			(stroke
				(width 0.1524)
				(type default)
			)
			(layer "F.SilkS")
		)
		(fp_line
			(start -0.7874 -0.4064)
			(end 0.7874 -0.4064)
			(stroke
				(width 0.1524)
				(type default)
			)
			(layer "F.SilkS")
		)
		(fp_line
			(start 0.7874 -0.4064)
			(end 0.7874 0.4064)
			(stroke
				(width 0.1524)
				(type default)
			)
			(layer "F.SilkS")
		)
		(fp_line
			(start -0.67945 0.3048)
			(end -0.67945 -0.305054)
			(stroke
				(width 0.1)
				(type default)
			)
			(layer "F.Fab")
		)
		(fp_line
			(start -0.12065 0.3048)
			(end -0.67945 0.3048)
			(stroke
				(width 0.1)
				(type default)
			)
			(layer "F.Fab")
		)
		(fp_line
			(start 0.120396 0.3048)
			(end 0.120396 0.2794)
			(stroke
				(width 0.1)
				(type default)
			)
			(layer "F.Fab")
		)
		(fp_line
			(start 0.67945 0.3048)
			(end 0.120396 0.3048)
			(stroke
				(width 0.1)
				(type default)
			)
			(layer "F.Fab")
		)
		(fp_line
			(start -0.12065 0.2794)
			(end -0.12065 0.3048)
			(stroke
				(width 0.1)
				(type default)
			)
			(layer "F.Fab")
		)
		(fp_line
			(start 0.120396 0.2794)
			(end -0.12065 0.2794)
			(stroke
				(width 0.1)
				(type default)
			)
			(layer "F.Fab")
		)
		(fp_line
			(start -0.12065 -0.2794)
			(end 0.12065 -0.2794)
			(stroke
				(width 0.1)
				(type default)
			)
			(layer "F.Fab")
		)
		(fp_line
			(start 0.12065 -0.2794)
			(end 0.12065 -0.3048)
			(stroke
				(width 0.1)
				(type default)
			)
			(layer "F.Fab")
		)
		(fp_line
			(start 0.12065 -0.3048)
			(end 0.67945 -0.3048)
			(stroke
				(width 0.1)
				(type default)
			)
			(layer "F.Fab")
		)
		(fp_line
			(start 0.67945 -0.3048)
			(end 0.67945 0.3048)
			(stroke
				(width 0.1)
				(type default)
			)
			(layer "F.Fab")
		)
		(fp_line
			(start -0.67945 -0.305054)
			(end -0.12065 -0.305054)
			(stroke
				(width 0.1)
				(type default)
			)
			(layer "F.Fab")
		)
		(fp_line
			(start -0.12065 -0.305054)
			(end -0.12065 -0.2794)
			(stroke
				(width 0.1)
				(type default)
			)
			(layer "F.Fab")
		)
		(pad "1" smd circle
			(at -0.40005 0 270)
			(size 0 0)
			(layers "F.Cu" "F.Mask" "F.Paste")
			(net "PVCCFA_EHV_FIVRA_CPU0_PVCC2")
		)
		(pad "2" smd circle
			(at 0.40005 0 270)
			(size 0 0)
			(layers "F.Cu" "F.Mask" "F.Paste")
			(net "GND")
		)
	)
)
